# T6G (Grand Teton) — schematic netlist excerpt (pin names and nets, part order shuffled) for the footprints in the layout excerpt that follows; sources: Cadence DE-HDL packaged netlist, KiCad conversion of 04192023_DAF0TMB3IC0_F0TG_MB_C_brd_V02_OCP.brd

R4451  Q_RES  33.2 1% CHIP  pkg 0402LF  page 176 : A = RST_USB_HUB_N ; B = RST_USB_CPU0_HUB1_R_N
PC126  Q_CAP  1UF 25V 10% X6S  pkg C0402  page 192 : A = SW_P12V_AUX_PVDD_33_S5_FLT ; B = GND

(kicad_pcb
	(version 20260206)
	(generator "pcbnew")
	(generator_version "10.0")
	(general
		(thickness 1.6)
		(legacy_teardrops no)
	)
	(paper "A4")
	(title_block
		(title "04192023_DAF0TMB3IC0_F0TG_MB_C_brd_V02_OCP.brd")
		(comment 1 "Grand Teton / footprints 3577-3578 of 8354")
	)
	(layers
		(0 "F.Cu" signal "TOP")
		(4 "In1.Cu" signal "GND")
		(6 "In2.Cu" signal "IN1")
		(8 "In3.Cu" signal "GND1")
		(10 "In4.Cu" signal "IN2")
		(12 "In5.Cu" signal "GND2")
		(14 "In6.Cu" signal "IN3")
		(16 "In7.Cu" signal "GND3")
		(18 "In8.Cu" signal "VCC")
		(20 "In9.Cu" signal "VCC1")
		(22 "In10.Cu" signal "GND4")
		(24 "In11.Cu" signal "IN4")
		(26 "In12.Cu" signal "GND5")
		(28 "In13.Cu" signal "IN5")
		(30 "In14.Cu" signal "GND6")
		(32 "In15.Cu" signal "IN6")
		(34 "In16.Cu" signal "GND7")
		(2 "B.Cu" signal "BOTTOM")
		(9 "F.Adhes" user "F.Adhesive")
		(11 "B.Adhes" user "B.Adhesive")
		(13 "F.Paste" user "Package Geometry/Pastemask Top")
		(15 "B.Paste" user "Package Geometry/Pastemask Bottom")
		(5 "F.SilkS" user "Ref Des/Silkscreen Top")
		(7 "B.SilkS" user "Ref Des/Silkscreen Bottom")
		(1 "F.Mask" user "Board Geometry/Soldermask Top")
		(3 "B.Mask" user "Board Geometry/Soldermask Bottom")
		(17 "Dwgs.User" user "User.Drawings")
		(19 "Cmts.User" user "User.Comments")
		(21 "Eco1.User" user "User.Eco1")
		(23 "Eco2.User" user "User.Eco2")
		(25 "Edge.Cuts" user "Board Geometry/Outline")
		(27 "Margin" user)
		(31 "F.CrtYd" user "Package Geometry/Place Bound Top")
		(29 "B.CrtYd" user "Package Geometry/Place Bound Bottom")
		(35 "F.Fab" user "Ref Des/Assembly Top")
		(33 "B.Fab" user "Ref Des/Assembly Bottom")
	)
	(footprint ""
		(layer "F.Cu")
		(at 201.636884 -337.480148)
		(property "Reference" "PC126"
			(at 0 0 0)
			(layer "F.SilkS")
			(hide yes)
			(effects
				(font
					(size 1.27 1.27)
				)
			)
		)
		(property "Value" ""
			(at 0 0 0)
			(layer "F.Fab")
			(effects
				(font
					(size 1.27 1.27)
				)
			)
		)
		(duplicate_pad_numbers_are_jumpers no)
		(fp_line
			(start -0.7874 -0.4064)
			(end 0.7874 -0.4064)
			(stroke
				(width 0.1524)
				(type default)
			)
			(layer "F.SilkS")
		)
		(fp_line
			(start -0.7874 0.4064)
			(end -0.7874 -0.4064)
			(stroke
				(width 0.1524)
				(type default)
			)
			(layer "F.SilkS")
		)
		(fp_line
			(start 0.7874 -0.4064)
			(end 0.7874 0.4064)
			(stroke
				(width 0.1524)
				(type default)
			)
			(layer "F.SilkS")
		)
		(fp_line
			(start 0.7874 0.4064)
			(end -0.7874 0.4064)
			(stroke
				(width 0.1524)
				(type default)
			)
			(layer "F.SilkS")
		)
		(fp_line
			(start -0.67945 -0.305054)
			(end -0.12065 -0.305054)
			(stroke
				(width 0.1)
				(type default)
			)
			(layer "F.Fab")
		)
		(fp_line
			(start -0.67945 0.3048)
			(end -0.67945 -0.305054)
			(stroke
				(width 0.1)
				(type default)
			)
			(layer "F.Fab")
		)
		(fp_line
			(start -0.12065 -0.305054)
			(end -0.12065 -0.2794)
			(stroke
				(width 0.1)
				(type default)
			)
			(layer "F.Fab")
		)
		(fp_line
			(start -0.12065 -0.2794)
			(end 0.12065 -0.2794)
			(stroke
				(width 0.1)
				(type default)
			)
			(layer "F.Fab")
		)
		(fp_line
			(start -0.12065 0.2794)
			(end -0.12065 0.3048)
			(stroke
				(width 0.1)
				(type default)
			)
			(layer "F.Fab")
		)
		(fp_line
			(start -0.12065 0.3048)
			(end -0.67945 0.3048)
			(stroke
				(width 0.1)
				(type default)
			)
			(layer "F.Fab")
		)
		(fp_line
			(start 0.120396 0.2794)
			(end -0.12065 0.2794)
			(stroke
				(width 0.1)
				(type default)
			)
			(layer "F.Fab")
		)
		(fp_line
			(start 0.120396 0.3048)
			(end 0.120396 0.2794)
			(stroke
				(width 0.1)
				(type default)
			)
			(layer "F.Fab")
		)
		(fp_line
			(start 0.12065 -0.3048)
			(end 0.67945 -0.3048)
			(stroke
				(width 0.1)
				(type default)
			)
			(layer "F.Fab")
		)
		(fp_line
			(start 0.12065 -0.2794)
			(end 0.12065 -0.3048)
			(stroke
				(width 0.1)
				(type default)
			)
			(layer "F.Fab")
		)
		(fp_line
			(start 0.67945 -0.3048)
			(end 0.67945 0.3048)
			(stroke
				(width 0.1)
				(type default)
			)
			(layer "F.Fab")
		)
		(fp_line
			(start 0.67945 0.3048)
			(end 0.120396 0.3048)
			(stroke
				(width 0.1)
				(type default)
			)
			(layer "F.Fab")
		)
		(pad "1" smd circle
			(at -0.40005 0)
			(size 0 0)
			(layers "F.Cu" "F.Mask" "F.Paste")
			(net "SW_P12V_AUX_PVDD_33_S5_FLT")
		)
		(pad "2" smd circle
			(at 0.40005 0)
			(size 0 0)
			(layers "F.Cu" "F.Mask" "F.Paste")
			(net "GND")
		)
	)
	(footprint ""
		(layer "F.Cu")
		(at 124.633228 -48.137064)
		(property "Reference" "R4451"
			(at 0 0 0)
			(layer "F.SilkS")
			(hide yes)
			(effects
				(font
					(size 1.27 1.27)
				)
			)
		)
		(property "Value" ""
			(at 0 0 0)
			(layer "F.Fab")
			(effects
				(font
					(size 1.27 1.27)
				)
			)
		)
		(duplicate_pad_numbers_are_jumpers no)
		(fp_line
			(start -0.7874 -0.4064)
			(end 0.7874 -0.4064)
			(stroke
				(width 0.1524)
				(type default)
			)
			(layer "F.SilkS")
		)
		(fp_line
			(start -0.7874 0.4064)
			(end -0.7874 -0.4064)
			(stroke
				(width 0.1524)
				(type default)
			)
			(layer "F.SilkS")
		)
		(fp_line
			(start 0.7874 -0.4064)
			(end 0.7874 0.4064)
			(stroke
				(width 0.1524)
				(type default)
			)
			(layer "F.SilkS")
		)
		(fp_line
			(start 0.7874 0.4064)
			(end -0.7874 0.4064)
			(stroke
				(width 0.1524)
				(type default)
			)
			(layer "F.SilkS")
		)
		(fp_line
			(start -0.67945 -0.305054)
			(end -0.12065 -0.305054)
			(stroke
				(width 0.1)
				(type default)
			)
			(layer "F.Fab")
		)
		(fp_line
			(start -0.67945 0.3048)
			(end -0.67945 -0.305054)
			(stroke
				(width 0.1)
				(type default)
			)
			(layer "F.Fab")
		)
		(fp_line
			(start -0.12065 -0.305054)
			(end -0.12065 -0.2794)
			(stroke
				(width 0.1)
				(type default)
			)
			(layer "F.Fab")
		)
		(fp_line
			(start -0.12065 -0.2794)
			(end 0.12065 -0.2794)
			(stroke
				(width 0.1)
				(type default)
			)
			(layer "F.Fab")
		)
		(fp_line
			(start -0.12065 0.2794)
			(end -0.12065 0.3048)
			(stroke
				(width 0.1)
				(type default)
			)
			(layer "F.Fab")
		)
		(fp_line
			(start -0.12065 0.3048)
			(end -0.67945 0.3048)
			(stroke
				(width 0.1)
				(type default)
			)
			(layer "F.Fab")
		)
		(fp_line
			(start 0.120396 0.2794)
			(end -0.12065 0.2794)
			(stroke
				(width 0.1)
				(type default)
			)
			(layer "F.Fab")
		)
		(fp_line
			(start 0.120396 0.3048)
			(end 0.120396 0.2794)
			(stroke
				(width 0.1)
				(type default)
			)
			(layer "F.Fab")
		)
		(fp_line
			(start 0.12065 -0.3048)
			(end 0.67945 -0.3048)
			(stroke
				(width 0.1)
				(type default)
			)
			(layer "F.Fab")
		)
		(fp_line
			(start 0.12065 -0.2794)
			(end 0.12065 -0.3048)
			(stroke
				(width 0.1)
				(type default)
			)
			(layer "F.Fab")
		)
		(fp_line
			(start 0.67945 -0.3048)
			(end 0.67945 0.3048)
			(stroke
				(width 0.1)
				(type default)
			)
			(layer "F.Fab")
		)
		(fp_line
			(start 0.67945 0.3048)
			(end 0.120396 0.3048)
			(stroke
				(width 0.1)
				(type default)
			)
			(layer "F.Fab")
		)
		(pad "1" smd circle
			(at -0.40005 0)
			(size 0 0)
			(layers "F.Cu" "F.Mask" "F.Paste")
			(net "RST_USB_HUB_N")
		)
		(pad "2" smd circle
			(at 0.40005 0)
			(size 0 0)
			(layers "F.Cu" "F.Mask" "F.Paste")
			(net "RST_USB_CPU0_HUB1_R_N")
		)
	)
)
